(kicad_pcb
	(version 20260206)
	(generator "pcbnew")
	(generator_version "10.0")
	(general
		(thickness 1.6)
		(legacy_teardrops no)
	)
	(paper "A4")
	(title_block
		(title "03242023_DA0F0TMBIJ0_F0T_Motherboard_J_brd_V01_OCP.brd")
		(comment 1 "Grand Teton / footprints 2914-2919 of 6105")
	)
	(layers
		(0 "F.Cu" signal "TOP")
		(4 "In1.Cu" signal "GND")
		(6 "In2.Cu" signal "IN1")
		(8 "In3.Cu" signal "GND1")
		(10 "In4.Cu" signal "IN2")
		(12 "In5.Cu" signal "GND2")
		(14 "In6.Cu" signal "IN3")
		(16 "In7.Cu" signal "GND3")
		(18 "In8.Cu" signal "VCC")
		(20 "In9.Cu" signal "VCC1")
		(22 "In10.Cu" signal "GND4")
		(24 "In11.Cu" signal "IN4")
		(26 "In12.Cu" signal "GND5")
		(28 "In13.Cu" signal "IN5")
		(30 "In14.Cu" signal "GND6")
		(32 "In15.Cu" signal "IN6")
		(34 "In16.Cu" signal "GND7")
		(2 "B.Cu" signal "BOTTOM")
		(9 "F.Adhes" user "F.Adhesive")
		(11 "B.Adhes" user "B.Adhesive")
		(13 "F.Paste" user "Package Geometry/Pastemask Top")
		(15 "B.Paste" user "Package Geometry/Pastemask Bottom")
		(5 "F.SilkS" user "Ref Des/Silkscreen Top")
		(7 "B.SilkS" user "Ref Des/Silkscreen Bottom")
		(1 "F.Mask" user "Board Geometry/Soldermask Top")
		(3 "B.Mask" user "Board Geometry/Soldermask Bottom")
		(17 "Dwgs.User" user "User.Drawings")
		(19 "Cmts.User" user "User.Comments")
		(21 "Eco1.User" user "User.Eco1")
		(23 "Eco2.User" user "User.Eco2")
		(25 "Edge.Cuts" user "Board Geometry/Outline")
		(27 "Margin" user)
		(31 "F.CrtYd" user "Package Geometry/Place Bound Top")
		(29 "B.CrtYd" user "Package Geometry/Place Bound Bottom")
		(35 "F.Fab" user "Ref Des/Assembly Top")
		(33 "B.Fab" user "Ref Des/Assembly Bottom")
	)
	(footprint ""
		(layer "F.Cu")
		(at 317.7921 -76.585064 90)
		(property "Reference" "R2243"
			(at 0 0 90)
			(layer "F.SilkS")
			(hide yes)
			(effects
				(font
					(size 1.27 1.27)
				)
			)
		)
		(property "Value" ""
			(at 0 0 90)
			(layer "F.Fab")
			(effects
				(font
					(size 1.27 1.27)
				)
			)
		)
		(duplicate_pad_numbers_are_jumpers no)
		(fp_line
			(start 0.7874 -0.4064)
			(end 0.7874 0.4064)
			(stroke
				(width 0.1524)
				(type default)
			)
			(layer "F.SilkS")
		)
		(fp_line
			(start -0.7874 -0.4064)
			(end 0.7874 -0.4064)
			(stroke
				(width 0.1524)
				(type default)
			)
			(layer "F.SilkS")
		)
		(fp_line
			(start 0.7874 0.4064)
			(end -0.7874 0.4064)
			(stroke
				(width 0.1524)
				(type default)
			)
			(layer "F.SilkS")
		)
		(fp_line
			(start -0.7874 0.4064)
			(end -0.7874 -0.4064)
			(stroke
				(width 0.1524)
				(type default)
			)
			(layer "F.SilkS")
		)
		(fp_line
			(start -0.12065 -0.305054)
			(end -0.12065 -0.2794)
			(stroke
				(width 0.1)
				(type default)
			)
			(layer "F.Fab")
		)
		(fp_line
			(start -0.67945 -0.305054)
			(end -0.12065 -0.305054)
			(stroke
				(width 0.1)
				(type default)
			)
			(layer "F.Fab")
		)
		(fp_line
			(start 0.67945 -0.3048)
			(end 0.67945 0.3048)
			(stroke
				(width 0.1)
				(type default)
			)
			(layer "F.Fab")
		)
		(fp_line
			(start 0.12065 -0.3048)
			(end 0.67945 -0.3048)
			(stroke
				(width 0.1)
				(type default)
			)
			(layer "F.Fab")
		)
		(fp_line
			(start 0.12065 -0.2794)
			(end 0.12065 -0.3048)
			(stroke
				(width 0.1)
				(type default)
			)
			(layer "F.Fab")
		)
		(fp_line
			(start -0.12065 -0.2794)
			(end 0.12065 -0.2794)
			(stroke
				(width 0.1)
				(type default)
			)
			(layer "F.Fab")
		)
		(fp_line
			(start 0.120396 0.2794)
			(end -0.12065 0.2794)
			(stroke
				(width 0.1)
				(type default)
			)
			(layer "F.Fab")
		)
		(fp_line
			(start -0.12065 0.2794)
			(end -0.12065 0.3048)
			(stroke
				(width 0.1)
				(type default)
			)
			(layer "F.Fab")
		)
		(fp_line
			(start 0.67945 0.3048)
			(end 0.120396 0.3048)
			(stroke
				(width 0.1)
				(type default)
			)
			(layer "F.Fab")
		)
		(fp_line
			(start 0.120396 0.3048)
			(end 0.120396 0.2794)
			(stroke
				(width 0.1)
				(type default)
			)
			(layer "F.Fab")
		)
		(fp_line
			(start -0.12065 0.3048)
			(end -0.67945 0.3048)
			(stroke
				(width 0.1)
				(type default)
			)
			(layer "F.Fab")
		)
		(fp_line
			(start -0.67945 0.3048)
			(end -0.67945 -0.305054)
			(stroke
				(width 0.1)
				(type default)
			)
			(layer "F.Fab")
		)
		(pad "1" smd circle
			(at -0.40005 0 90)
			(size 0 0)
			(layers "F.Cu" "F.Mask" "F.Paste")
			(net "FM_BOARD_SKU_ID0")
		)
		(pad "2" smd circle
			(at 0.40005 0 90)
			(size 0 0)
			(layers "F.Cu" "F.Mask" "F.Paste")
			(net "GND")
		)
	)
	(footprint ""
		(layer "F.Cu")
		(at 265.172952 -127.548894)
		(property "Reference" "R4500"
			(at 0 0 0)
			(layer "F.SilkS")
			(hide yes)
			(effects
				(font
					(size 1.27 1.27)
				)
			)
		)
		(property "Value" ""
			(at 0 0 0)
			(layer "F.Fab")
			(effects
				(font
					(size 1.27 1.27)
				)
			)
		)
		(duplicate_pad_numbers_are_jumpers no)
		(fp_line
			(start -0.7874 -0.4064)
			(end 0.7874 -0.4064)
			(stroke
				(width 0.1524)
				(type default)
			)
			(layer "F.SilkS")
		)
		(fp_line
			(start -0.7874 0.4064)
			(end -0.7874 -0.4064)
			(stroke
				(width 0.1524)
				(type default)
			)
			(layer "F.SilkS")
		)
		(fp_line
			(start 0.7874 -0.4064)
			(end 0.7874 0.4064)
			(stroke
				(width 0.1524)
				(type default)
			)
			(layer "F.SilkS")
		)
		(fp_line
			(start 0.7874 0.4064)
			(end -0.7874 0.4064)
			(stroke
				(width 0.1524)
				(type default)
			)
			(layer "F.SilkS")
		)
		(fp_line
			(start -0.67945 -0.305054)
			(end -0.12065 -0.305054)
			(stroke
				(width 0.1)
				(type default)
			)
			(layer "F.Fab")
		)
		(fp_line
			(start -0.67945 0.3048)
			(end -0.67945 -0.305054)
			(stroke
				(width 0.1)
				(type default)
			)
			(layer "F.Fab")
		)
		(fp_line
			(start -0.12065 -0.305054)
			(end -0.12065 -0.2794)
			(stroke
				(width 0.1)
				(type default)
			)
			(layer "F.Fab")
		)
		(fp_line
			(start -0.12065 -0.2794)
			(end 0.12065 -0.2794)
			(stroke
				(width 0.1)
				(type default)
			)
			(layer "F.Fab")
		)
		(fp_line
			(start -0.12065 0.2794)
			(end -0.12065 0.3048)
			(stroke
				(width 0.1)
				(type default)
			)
			(layer "F.Fab")
		)
		(fp_line
			(start -0.12065 0.3048)
			(end -0.67945 0.3048)
			(stroke
				(width 0.1)
				(type default)
			)
			(layer "F.Fab")
		)
		(fp_line
			(start 0.120396 0.2794)
			(end -0.12065 0.2794)
			(stroke
				(width 0.1)
				(type default)
			)
			(layer "F.Fab")
		)
		(fp_line
			(start 0.120396 0.3048)
			(end 0.120396 0.2794)
			(stroke
				(width 0.1)
				(type default)
			)
			(layer "F.Fab")
		)
		(fp_line
			(start 0.12065 -0.3048)
			(end 0.67945 -0.3048)
			(stroke
				(width 0.1)
				(type default)
			)
			(layer "F.Fab")
		)
		(fp_line
			(start 0.12065 -0.2794)
			(end 0.12065 -0.3048)
			(stroke
				(width 0.1)
				(type default)
			)
			(layer "F.Fab")
		)
		(fp_line
			(start 0.67945 -0.3048)
			(end 0.67945 0.3048)
			(stroke
				(width 0.1)
				(type default)
			)
			(layer "F.Fab")
		)
		(fp_line
			(start 0.67945 0.3048)
			(end 0.120396 0.3048)
			(stroke
				(width 0.1)
				(type default)
			)
			(layer "F.Fab")
		)
		(pad "1" smd circle
			(at -0.40005 0)
			(size 0 0)
			(layers "F.Cu" "F.Mask" "F.Paste")
			(net "P3V3")
		)
		(pad "2" smd circle
			(at 0.40005 0)
			(size 0 0)
			(layers "F.Cu" "F.Mask" "F.Paste")
			(net "PU_CLK_BUF_ISO_EN")
		)
	)
	(footprint ""
		(layer "F.Cu")
		(at 361.288838 -324.445376)
		(property "Reference" "PL112"
			(at 15.670022 5.810758 0)
			(unlocked yes)
			(layer "F.SilkS")
			(effects
				(font
					(size 0.7874 0.5842)
					(thickness 0.1524)
				)
				(justify left)
			)
		)
		(property "Value" ""
			(at 0 0 0)
			(layer "F.Fab")
			(effects
				(font
					(size 1.27 1.27)
				)
			)
		)
		(duplicate_pad_numbers_are_jumpers no)
		(fp_line
			(start -3.750056 -5.500116)
			(end -2.393442 -5.500116)
			(stroke
				(width 0.1524)
				(type default)
			)
			(layer "F.SilkS")
		)
		(fp_line
			(start -3.750056 5.500116)
			(end -3.750056 -5.500116)
			(stroke
				(width 0.1524)
				(type default)
			)
			(layer "F.SilkS")
		)
		(fp_line
			(start -2.393442 5.500116)
			(end -3.750056 5.500116)
			(stroke
				(width 0.1524)
				(type default)
			)
			(layer "F.SilkS")
		)
		(fp_line
			(start 2.393442 5.500116)
			(end 3.750056 5.500116)
			(stroke
				(width 0.1524)
				(type default)
			)
			(layer "F.SilkS")
		)
		(fp_line
			(start 3.750056 -5.500116)
			(end 2.393442 -5.500116)
			(stroke
				(width 0.1524)
				(type default)
			)
			(layer "F.SilkS")
		)
		(fp_line
			(start 3.750056 -4.449572)
			(end 3.750056 -5.500116)
			(stroke
				(width 0.1524)
				(type default)
			)
			(layer "F.SilkS")
		)
		(fp_line
			(start 3.750056 5.500116)
			(end 3.750056 -3.687572)
			(stroke
				(width 0.1524)
				(type default)
			)
			(layer "F.SilkS")
		)
		(fp_poly
			(pts
				(xy -3.380994 -7.001764) (xy -3.021838 -5.924042) (xy -4.099306 -6.283198)
			)
			(stroke
				(width 0)
				(type default)
			)
			(fill yes)
			(layer "F.SilkS")
		)
		(fp_line
			(start -3.750056 -5.500116)
			(end -3.750056 5.500116)
			(stroke
				(width 0.1)
				(type default)
			)
			(layer "F.Fab")
		)
		(fp_line
			(start -3.750056 5.500116)
			(end 3.750056 5.500116)
			(stroke
				(width 0.1)
				(type default)
			)
			(layer "F.Fab")
		)
		(fp_line
			(start 3.750056 -5.500116)
			(end -3.750056 -5.500116)
			(stroke
				(width 0.1)
				(type default)
			)
			(layer "F.Fab")
		)
		(fp_line
			(start 3.750056 5.500116)
			(end 3.750056 -5.500116)
			(stroke
				(width 0.1)
				(type default)
			)
			(layer "F.Fab")
		)
		(fp_poly
			(pts
				(xy -4.9276 -4.757928) (xy -4.9276 -3.741928) (xy -3.9116 -4.249928)
			)
			(stroke
				(width 0)
				(type default)
			)
			(fill yes)
			(layer "F.Fab")
		)
		(pad "1" smd rect
			(at 0 -4.249928 270)
			(size 2.413 4.5212)
			(layers "F.Cu" "F.Mask" "F.Paste")
			(net "SW_PVCCIN_CPU0_SW3")
		)
		(pad "2" smd rect
			(at 0 -1.175004 270)
			(size 1.3716 4.5212)
			(layers "F.Cu" "F.Mask" "F.Paste")
			(net "IND_P0_CPL3")
		)
		(pad "3" smd rect
			(at 0 1.175004 270)
			(size 1.3716 4.5212)
			(layers "F.Cu" "F.Mask" "F.Paste")
			(net "IND_P0_CPL4")
		)
		(pad "4" smd rect
			(at 0 4.249928 270)
			(size 2.413 4.5212)
			(layers "F.Cu" "F.Mask" "F.Paste")
			(net "PVCCIN_CPU0")
		)
	)
	(footprint ""
		(layer "F.Cu")
		(at 366.48263 -251.375418 90)
		(property "Reference" "C1040"
			(at 0 0 90)
			(layer "F.SilkS")
			(hide yes)
			(effects
				(font
					(size 1.27 1.27)
				)
			)
		)
		(property "Value" ""
			(at 0 0 90)
			(layer "F.Fab")
			(effects
				(font
					(size 1.27 1.27)
				)
			)
		)
		(duplicate_pad_numbers_are_jumpers no)
		(fp_line
			(start 0.7874 -0.4064)
			(end 0.7874 0.4064)
			(stroke
				(width 0.1524)
				(type default)
			)
			(layer "F.SilkS")
		)
		(fp_line
			(start -0.7874 -0.4064)
			(end 0.7874 -0.4064)
			(stroke
				(width 0.1524)
				(type default)
			)
			(layer "F.SilkS")
		)
		(fp_line
			(start 0.7874 0.4064)
			(end -0.7874 0.4064)
			(stroke
				(width 0.1524)
				(type default)
			)
			(layer "F.SilkS")
		)
		(fp_line
			(start -0.7874 0.4064)
			(end -0.7874 -0.4064)
			(stroke
				(width 0.1524)
				(type default)
			)
			(layer "F.SilkS")
		)
		(fp_line
			(start -0.12065 -0.305054)
			(end -0.12065 -0.2794)
			(stroke
				(width 0.1)
				(type default)
			)
			(layer "F.Fab")
		)
		(fp_line
			(start -0.67945 -0.305054)
			(end -0.12065 -0.305054)
			(stroke
				(width 0.1)
				(type default)
			)
			(layer "F.Fab")
		)
		(fp_line
			(start 0.67945 -0.3048)
			(end 0.67945 0.3048)
			(stroke
				(width 0.1)
				(type default)
			)
			(layer "F.Fab")
		)
		(fp_line
			(start 0.12065 -0.3048)
			(end 0.67945 -0.3048)
			(stroke
				(width 0.1)
				(type default)
			)
			(layer "F.Fab")
		)
		(fp_line
			(start 0.12065 -0.2794)
			(end 0.12065 -0.3048)
			(stroke
				(width 0.1)
				(type default)
			)
			(layer "F.Fab")
		)
		(fp_line
			(start -0.12065 -0.2794)
			(end 0.12065 -0.2794)
			(stroke
				(width 0.1)
				(type default)
			)
			(layer "F.Fab")
		)
		(fp_line
			(start 0.120396 0.2794)
			(end -0.12065 0.2794)
			(stroke
				(width 0.1)
				(type default)
			)
			(layer "F.Fab")
		)
		(fp_line
			(start -0.12065 0.2794)
			(end -0.12065 0.3048)
			(stroke
				(width 0.1)
				(type default)
			)
			(layer "F.Fab")
		)
		(fp_line
			(start 0.67945 0.3048)
			(end 0.120396 0.3048)
			(stroke
				(width 0.1)
				(type default)
			)
			(layer "F.Fab")
		)
		(fp_line
			(start 0.120396 0.3048)
			(end 0.120396 0.2794)
			(stroke
				(width 0.1)
				(type default)
			)
			(layer "F.Fab")
		)
		(fp_line
			(start -0.12065 0.3048)
			(end -0.67945 0.3048)
			(stroke
				(width 0.1)
				(type default)
			)
			(layer "F.Fab")
		)
		(fp_line
			(start -0.67945 0.3048)
			(end -0.67945 -0.305054)
			(stroke
				(width 0.1)
				(type default)
			)
			(layer "F.Fab")
		)
		(pad "1" smd circle
			(at -0.40005 0 90)
			(size 0 0)
			(layers "F.Cu" "F.Mask" "F.Paste")
			(net "PVCCIN_CPU0")
		)
		(pad "2" smd circle
			(at 0.40005 0 90)
			(size 0 0)
			(layers "F.Cu" "F.Mask" "F.Paste")
			(net "GND")
		)
	)
	(footprint ""
		(layer "F.Cu")
		(at 164.64788 -107.025948 180)
		(property "Reference" "R2939"
			(at 0 0 180)
			(layer "F.SilkS")
			(hide yes)
			(effects
				(font
					(size 1.27 1.27)
				)
			)
		)
		(property "Value" ""
			(at 0 0 180)
			(layer "F.Fab")
			(effects
				(font
					(size 1.27 1.27)
				)
			)
		)
		(duplicate_pad_numbers_are_jumpers no)
		(fp_line
			(start 0.7874 0.4064)
			(end -0.7874 0.4064)
			(stroke
				(width 0.1524)
				(type default)
			)
			(layer "F.SilkS")
		)
		(fp_line
			(start 0.7874 -0.4064)
			(end 0.7874 0.4064)
			(stroke
				(width 0.1524)
				(type default)
			)
			(layer "F.SilkS")
		)
		(fp_line
			(start -0.7874 0.4064)
			(end -0.7874 -0.4064)
			(stroke
				(width 0.1524)
				(type default)
			)
			(layer "F.SilkS")
		)
		(fp_line
			(start -0.7874 -0.4064)
			(end 0.7874 -0.4064)
			(stroke
				(width 0.1524)
				(type default)
			)
			(layer "F.SilkS")
		)
		(fp_line
			(start 0.67945 0.3048)
			(end 0.120396 0.3048)
			(stroke
				(width 0.1)
				(type default)
			)
			(layer "F.Fab")
		)
		(fp_line
			(start 0.67945 -0.3048)
			(end 0.67945 0.3048)
			(stroke
				(width 0.1)
				(type default)
			)
			(layer "F.Fab")
		)
		(fp_line
			(start 0.12065 -0.2794)
			(end 0.12065 -0.3048)
			(stroke
				(width 0.1)
				(type default)
			)
			(layer "F.Fab")
		)
		(fp_line
			(start 0.12065 -0.3048)
			(end 0.67945 -0.3048)
			(stroke
				(width 0.1)
				(type default)
			)
			(layer "F.Fab")
		)
		(fp_line
			(start 0.120396 0.3048)
			(end 0.120396 0.2794)
			(stroke
				(width 0.1)
				(type default)
			)
			(layer "F.Fab")
		)
		(fp_line
			(start 0.120396 0.2794)
			(end -0.12065 0.2794)
			(stroke
				(width 0.1)
				(type default)
			)
			(layer "F.Fab")
		)
		(fp_line
			(start -0.12065 0.3048)
			(end -0.67945 0.3048)
			(stroke
				(width 0.1)
				(type default)
			)
			(layer "F.Fab")
		)
		(fp_line
			(start -0.12065 0.2794)
			(end -0.12065 0.3048)
			(stroke
				(width 0.1)
				(type default)
			)
			(layer "F.Fab")
		)
		(fp_line
			(start -0.12065 -0.2794)
			(end 0.12065 -0.2794)
			(stroke
				(width 0.1)
				(type default)
			)
			(layer "F.Fab")
		)
		(fp_line
			(start -0.12065 -0.305054)
			(end -0.12065 -0.2794)
			(stroke
				(width 0.1)
				(type default)
			)
			(layer "F.Fab")
		)
		(fp_line
			(start -0.67945 0.3048)
			(end -0.67945 -0.305054)
			(stroke
				(width 0.1)
				(type default)
			)
			(layer "F.Fab")
		)
		(fp_line
			(start -0.67945 -0.305054)
			(end -0.12065 -0.305054)
			(stroke
				(width 0.1)
				(type default)
			)
			(layer "F.Fab")
		)
		(pad "1" smd circle
			(at -0.40005 0 180)
			(size 0 0)
			(layers "F.Cu" "F.Mask" "F.Paste")
			(net "FM_GPU_HSC_EN_R")
		)
		(pad "2" smd circle
			(at 0.40005 0 180)
			(size 0 0)
			(layers "F.Cu" "F.Mask" "F.Paste")
			(net "FM_GPU_HSC_EN")
		)
	)
	(footprint ""
		(layer "F.Cu")
		(at 345.79179 -69.36994 90)
		(property "Reference" "C150"
			(at 0 0 90)
			(layer "F.SilkS")
			(hide yes)
			(effects
				(font
					(size 1.27 1.27)
				)
			)
		)
		(property "Value" ""
			(at 0 0 90)
			(layer "F.Fab")
			(effects
				(font
					(size 1.27 1.27)
				)
			)
		)
		(duplicate_pad_numbers_are_jumpers no)
		(fp_line
			(start 0.299974 -0.150114)
			(end 0.299974 0.150114)
			(stroke
				(width 0.1)
				(type default)
			)
			(layer "F.Fab")
		)
		(fp_line
			(start -0.299974 -0.150114)
			(end 0.299974 -0.150114)
			(stroke
				(width 0.1)
				(type default)
			)
			(layer "F.Fab")
		)
		(fp_line
			(start 0.299974 0.150114)
			(end -0.299974 0.150114)
			(stroke
				(width 0.1)
				(type default)
			)
			(layer "F.Fab")
		)
		(fp_line
			(start -0.299974 0.150114)
			(end -0.299974 -0.150114)
			(stroke
				(width 0.1)
				(type default)
			)
			(layer "F.Fab")
		)
		(pad "1" smd rect
			(at -0.2667 0 90)
			(size 0.3048 0.381)
			(layers "F.Cu" "F.Mask" "F.Paste")
			(net "DMI_CPU0_PCH_TX_C_DP<2>")
		)
		(pad "2" smd rect
			(at 0.2667 0 90)
			(size 0.3048 0.381)
			(layers "F.Cu" "F.Mask" "F.Paste")
			(net "DMI_CPU0_PCH_TX_DP<2>")
		)
	)
)
